# BASEBOARD_FAB2 (Tioga Pass) — schematic netlist excerpt (pin names and nets, part order shuffled) for the footprints in the layout excerpt that follows; sources: Cadence DE-HDL packaged netlist, KiCad conversion of Wiwynn_Tioga_Pass_MB.brd

C2G11  CAP_A  47UF 4V 20% X5R  pkg 0603V  page 225 : A = PVDDQ_GHJ ; B = GND
R4D22  RES  27.4 1% CHIP  pkg 0402  page 103 : A = CLK_100M_CPU0_BCLK1_R_DP ; B = CLK_100M_CPU0_BCLK1_DP

(kicad_pcb
	(version 20260206)
	(generator "pcbnew")
	(generator_version "10.0")
	(general
		(thickness 1.6)
		(legacy_teardrops no)
	)
	(paper "A4")
	(title_block
		(title "Wiwynn_Tioga_Pass_MB.brd")
		(comment 1 "Tioga Pass / footprints 2324-2325 of 4770")
	)
	(layers
		(0 "F.Cu" signal "TOP")
		(4 "In1.Cu" signal "L2GND")
		(6 "In2.Cu" signal "L3")
		(8 "In3.Cu" signal "L4GND")
		(10 "In4.Cu" signal "L5")
		(12 "In5.Cu" signal "L6GND")
		(14 "In6.Cu" signal "L7VCC")
		(16 "In7.Cu" signal "L8VCC")
		(18 "In8.Cu" signal "L9GND")
		(20 "In9.Cu" signal "L10")
		(22 "In10.Cu" signal "L11GND")
		(24 "In11.Cu" signal "L12")
		(26 "In12.Cu" signal "L13GND")
		(2 "B.Cu" signal "BOTTOM")
		(9 "F.Adhes" user "F.Adhesive")
		(11 "B.Adhes" user "B.Adhesive")
		(13 "F.Paste" user "Package Geometry/Pastemask Top")
		(15 "B.Paste" user "Package Geometry/Pastemask Bottom")
		(5 "F.SilkS" user "Ref Des/Silkscreen Top")
		(7 "B.SilkS" user "Ref Des/Silkscreen Bottom")
		(1 "F.Mask" user "Board Geometry/Soldermask Top")
		(3 "B.Mask" user "Board Geometry/Soldermask Bottom")
		(17 "Dwgs.User" user "User.Drawings")
		(19 "Cmts.User" user "User.Comments")
		(21 "Eco1.User" user "User.Eco1")
		(23 "Eco2.User" user "User.Eco2")
		(25 "Edge.Cuts" user "Board Geometry/Outline")
		(27 "Margin" user)
		(31 "F.CrtYd" user "Package Geometry/Place Bound Top")
		(29 "B.CrtYd" user "Package Geometry/Place Bound Bottom")
		(35 "F.Fab" user "Ref Des/Assembly Top")
		(33 "B.Fab" user "Ref Des/Assembly Bottom")
	)
	(footprint ""
		(layer "F.Cu")
		(at 177.165 -78.867 90)
		(property "Reference" "R4D22"
			(at 0 0 90)
			(layer "F.SilkS")
			(hide yes)
			(effects
				(font
					(size 1.27 1.27)
				)
			)
		)
		(property "Value" ""
			(at 0 0 90)
			(layer "F.Fab")
			(effects
				(font
					(size 1.27 1.27)
				)
			)
		)
		(duplicate_pad_numbers_are_jumpers no)
		(fp_poly
			(pts
				(xy -0.2794 -0.1016) (xy 0.2794 -0.1016) (xy 0.2794 0.9906) (xy -0.2794 0.9906)
			)
			(stroke
				(width 0)
				(type default)
			)
			(fill no)
			(layer "F.CrtYd")
		)
		(fp_line
			(start 0.2794 -0.1016)
			(end -0.2794 -0.1016)
			(stroke
				(width 0.1)
				(type default)
			)
			(layer "F.Fab")
		)
		(fp_line
			(start -0.2794 -0.1016)
			(end -0.2794 0.9906)
			(stroke
				(width 0.1)
				(type default)
			)
			(layer "F.Fab")
		)
		(fp_line
			(start 0.2794 0.9906)
			(end 0.2794 -0.1016)
			(stroke
				(width 0.1)
				(type default)
			)
			(layer "F.Fab")
		)
		(fp_line
			(start -0.2794 0.9906)
			(end 0.2794 0.9906)
			(stroke
				(width 0.1)
				(type default)
			)
			(layer "F.Fab")
		)
		(pad "1" smd rect
			(at 0 0 90)
			(size 0.508 0.508)
			(layers "F.Cu" "F.Mask" "F.Paste")
			(net "CLK_100M_CPU0_BCLK1_R_DP")
		)
		(pad "2" smd rect
			(at 0 0.889 90)
			(size 0.508 0.508)
			(layers "F.Cu" "F.Mask" "F.Paste")
			(net "CLK_100M_CPU0_BCLK1_DP")
		)
		(zone
			(layer "F.Cu")
			(hatch none 0.5)
			(connect_pads
				(clearance 0)
			)
			(min_thickness 0.25)
			(keepout
				(tracks allowed)
				(vias not_allowed)
				(pads allowed)
				(copperpour not_allowed)
				(footprints allowed)
			)
			(placement
				(enabled no)
				(sheetname "")
			)
			(fill
				(thermal_gap 0.5)
				(thermal_bridge_width 0.5)
				(island_removal_mode 0)
			)
			(polygon
				(pts
					(xy 177.419 -78.613) (xy 177.419 -79.121) (xy 177.8 -79.121) (xy 177.8 -78.613)
				)
			)
		)
		(zone
			(layer "F.Cu")
			(hatch none 0.5)
			(connect_pads
				(clearance 0)
			)
			(min_thickness 0.25)
			(keepout
				(tracks not_allowed)
				(vias allowed)
				(pads allowed)
				(copperpour not_allowed)
				(footprints allowed)
			)
			(placement
				(enabled no)
				(sheetname "")
			)
			(fill
				(thermal_gap 0.5)
				(thermal_bridge_width 0.5)
				(island_removal_mode 0)
			)
			(polygon
				(pts
					(xy 177.8 -78.613) (xy 177.8 -79.121) (xy 177.419 -79.121) (xy 177.419 -78.613)
				)
			)
		)
	)
	(footprint ""
		(layer "F.Cu")
		(at 87.158068 -3.3528 -90)
		(property "Reference" "C2G11"
			(at 1.848866 0.752348 270)
			(unlocked yes)
			(layer "F.SilkS")
			(effects
				(font
					(size 1.27 0.9652)
					(thickness 0.1524)
				)
			)
		)
		(property "Value" ""
			(at 0 0 270)
			(layer "F.Fab")
			(effects
				(font
					(size 1.27 1.27)
				)
			)
		)
		(duplicate_pad_numbers_are_jumpers no)
		(fp_rect
			(start -0.500126 1.598422)
			(end 0.500126 -0.201422)
			(stroke
				(width 0)
				(type default)
			)
			(fill no)
			(layer "F.CrtYd")
		)
		(fp_line
			(start -0.500126 1.598422)
			(end -0.500126 -0.201422)
			(stroke
				(width 0.1)
				(type default)
			)
			(layer "F.Fab")
		)
		(fp_line
			(start 0.500126 1.598422)
			(end -0.500126 1.598422)
			(stroke
				(width 0.1)
				(type default)
			)
			(layer "F.Fab")
		)
		(fp_line
			(start -0.500126 -0.201422)
			(end 0.500126 -0.201422)
			(stroke
				(width 0.1)
				(type default)
			)
			(layer "F.Fab")
		)
		(fp_line
			(start 0.500126 -0.201422)
			(end 0.500126 1.598422)
			(stroke
				(width 0.1)
				(type default)
			)
			(layer "F.Fab")
		)
		(pad "1" smd rect
			(at 0 0 180)
			(size 0.889 0.9906)
			(layers "F.Cu" "F.Mask" "F.Paste")
			(net "PVDDQ_GHJ")
		)
		(pad "2" smd rect
			(at 0 1.397 180)
			(size 0.889 0.9906)
			(layers "F.Cu" "F.Mask" "F.Paste")
			(net "GND")
		)
		(zone
			(layer "F.Cu")
			(hatch none 0.5)
			(connect_pads
				(clearance 0)
			)
			(min_thickness 0.25)
			(keepout
				(tracks allowed)
				(vias not_allowed)
				(pads allowed)
				(copperpour not_allowed)
				(footprints allowed)
			)
			(placement
				(enabled no)
				(sheetname "")
			)
			(fill
				(thermal_gap 0.5)
				(thermal_bridge_width 0.5)
				(island_removal_mode 0)
			)
			(polygon
				(pts
					(xy 86.205568 -3.8481) (xy 86.205568 -2.8575) (xy 86.713568 -2.8575) (xy 86.713568 -3.8481)
				)
			)
		)
		(zone
			(layer "F.Cu")
			(hatch none 0.5)
			(connect_pads
				(clearance 0)
			)
			(min_thickness 0.25)
			(keepout
				(tracks not_allowed)
				(vias allowed)
				(pads allowed)
				(copperpour not_allowed)
				(footprints allowed)
			)
			(placement
				(enabled no)
				(sheetname "")
			)
			(fill
				(thermal_gap 0.5)
				(thermal_bridge_width 0.5)
				(island_removal_mode 0)
			)
			(polygon
				(pts
					(xy 86.205568 -3.8481) (xy 86.205568 -2.8575) (xy 86.713568 -2.8575) (xy 86.713568 -3.8481)
				)
			)
		)
	)
)
